# SCM (Grand Teton) — schematic netlist excerpt (pin names and nets, part order shuffled) for the footprints in the layout excerpt that follows; sources: Cadence DE-HDL packaged netlist, KiCad conversion of 12092022_DA0F0TMDCD0_F0T_Management_Board_D_brd_V3_OCP.brd

R786  Q_RES  2K 1% CHIP  pkg 0402LF  page 15 : A = P12V_SENSOR ; B = GND
C221  Q_CAP  0.1UF 25V 10% X7R  pkg 0402  page 20 : A = P1V2_AUX ; B = GND

(kicad_pcb
	(version 20260206)
	(generator "pcbnew")
	(generator_version "10.0")
	(general
		(thickness 1.6)
		(legacy_teardrops no)
	)
	(paper "A4")
	(title_block
		(title "12092022_DA0F0TMDCD0_F0T_Management_Board_D_brd_V3_OCP.brd")
		(comment 1 "Grand Teton / footprints 821-822 of 1440")
	)
	(layers
		(0 "F.Cu" signal "TOP")
		(4 "In1.Cu" signal "GND")
		(6 "In2.Cu" signal "IN1")
		(8 "In3.Cu" signal "GND1")
		(10 "In4.Cu" signal "IN2")
		(12 "In5.Cu" signal "VCC")
		(14 "In6.Cu" signal "VCC1")
		(16 "In7.Cu" signal "IN3")
		(18 "In8.Cu" signal "GND2")
		(20 "In9.Cu" signal "IN4")
		(22 "In10.Cu" signal "GND3")
		(2 "B.Cu" signal "BOTTOM")
		(9 "F.Adhes" user "F.Adhesive")
		(11 "B.Adhes" user "B.Adhesive")
		(13 "F.Paste" user "Package Geometry/Pastemask Top")
		(15 "B.Paste" user "Package Geometry/Pastemask Bottom")
		(5 "F.SilkS" user "Ref Des/Silkscreen Top")
		(7 "B.SilkS" user "Ref Des/Silkscreen Bottom")
		(1 "F.Mask" user "Board Geometry/Soldermask Top")
		(3 "B.Mask" user "Board Geometry/Soldermask Bottom")
		(17 "Dwgs.User" user "User.Drawings")
		(19 "Cmts.User" user "User.Comments")
		(21 "Eco1.User" user "User.Eco1")
		(23 "Eco2.User" user "User.Eco2")
		(25 "Edge.Cuts" user "Board Geometry/Outline")
		(27 "Margin" user)
		(31 "F.CrtYd" user "Package Geometry/Place Bound Top")
		(29 "B.CrtYd" user "Package Geometry/Place Bound Bottom")
		(35 "F.Fab" user "Ref Des/Assembly Top")
		(33 "B.Fab" user "Ref Des/Assembly Bottom")
	)
	(footprint ""
		(layer "B.Cu")
		(at 31.9532 -59.6392)
		(property "Reference" "R786"
			(at 0 0 0)
			(layer "B.SilkS")
			(hide yes)
			(effects
				(font
					(size 1.27 1.27)
				)
				(justify mirror)
			)
		)
		(property "Value" ""
			(at 0 0 0)
			(layer "B.Fab")
			(effects
				(font
					(size 1.27 1.27)
				)
				(justify mirror)
			)
		)
		(duplicate_pad_numbers_are_jumpers no)
		(fp_line
			(start -0.7874 -0.4064)
			(end -0.7874 0.4064)
			(stroke
				(width 0.1524)
				(type default)
			)
			(layer "B.SilkS")
		)
		(fp_line
			(start -0.7874 0.4064)
			(end 0.7874 0.4064)
			(stroke
				(width 0.1524)
				(type default)
			)
			(layer "B.SilkS")
		)
		(fp_line
			(start 0.7874 -0.4064)
			(end -0.7874 -0.4064)
			(stroke
				(width 0.1524)
				(type default)
			)
			(layer "B.SilkS")
		)
		(fp_line
			(start 0.7874 0.4064)
			(end 0.7874 -0.4064)
			(stroke
				(width 0.1524)
				(type default)
			)
			(layer "B.SilkS")
		)
		(fp_line
			(start -0.67945 -0.3048)
			(end -0.67945 0.3048)
			(stroke
				(width 0.1)
				(type default)
			)
			(layer "B.Fab")
		)
		(fp_line
			(start -0.67945 0.3048)
			(end -0.120396 0.3048)
			(stroke
				(width 0.1)
				(type default)
			)
			(layer "B.Fab")
		)
		(fp_line
			(start -0.12065 -0.3048)
			(end -0.67945 -0.3048)
			(stroke
				(width 0.1)
				(type default)
			)
			(layer "B.Fab")
		)
		(fp_line
			(start -0.12065 -0.2794)
			(end -0.12065 -0.3048)
			(stroke
				(width 0.1)
				(type default)
			)
			(layer "B.Fab")
		)
		(fp_line
			(start -0.120396 0.2794)
			(end 0.12065 0.2794)
			(stroke
				(width 0.1)
				(type default)
			)
			(layer "B.Fab")
		)
		(fp_line
			(start -0.120396 0.3048)
			(end -0.120396 0.2794)
			(stroke
				(width 0.1)
				(type default)
			)
			(layer "B.Fab")
		)
		(fp_line
			(start 0.12065 -0.305054)
			(end 0.12065 -0.2794)
			(stroke
				(width 0.1)
				(type default)
			)
			(layer "B.Fab")
		)
		(fp_line
			(start 0.12065 -0.2794)
			(end -0.12065 -0.2794)
			(stroke
				(width 0.1)
				(type default)
			)
			(layer "B.Fab")
		)
		(fp_line
			(start 0.12065 0.2794)
			(end 0.12065 0.3048)
			(stroke
				(width 0.1)
				(type default)
			)
			(layer "B.Fab")
		)
		(fp_line
			(start 0.12065 0.3048)
			(end 0.67945 0.3048)
			(stroke
				(width 0.1)
				(type default)
			)
			(layer "B.Fab")
		)
		(fp_line
			(start 0.67945 -0.305054)
			(end 0.12065 -0.305054)
			(stroke
				(width 0.1)
				(type default)
			)
			(layer "B.Fab")
		)
		(fp_line
			(start 0.67945 0.3048)
			(end 0.67945 -0.305054)
			(stroke
				(width 0.1)
				(type default)
			)
			(layer "B.Fab")
		)
		(pad "1" smd circle
			(at 0.40005 0 180)
			(size 0 0)
			(layers "B.Cu" "B.Mask" "B.Paste")
			(net "P12V_SENSOR")
		)
		(pad "2" smd circle
			(at -0.40005 0 180)
			(size 0 0)
			(layers "B.Cu" "B.Mask" "B.Paste")
			(net "GND")
		)
	)
	(footprint ""
		(layer "B.Cu")
		(at 79.57947 -54.898798)
		(property "Reference" "C221"
			(at 0 0 0)
			(layer "B.SilkS")
			(hide yes)
			(effects
				(font
					(size 1.27 1.27)
				)
				(justify mirror)
			)
		)
		(property "Value" ""
			(at 0 0 0)
			(layer "B.Fab")
			(effects
				(font
					(size 1.27 1.27)
				)
				(justify mirror)
			)
		)
		(duplicate_pad_numbers_are_jumpers no)
		(fp_line
			(start -0.7874 -0.4064)
			(end -0.7874 0.4064)
			(stroke
				(width 0.1524)
				(type default)
			)
			(layer "B.SilkS")
		)
		(fp_line
			(start -0.7874 0.4064)
			(end 0.7874 0.4064)
			(stroke
				(width 0.1524)
				(type default)
			)
			(layer "B.SilkS")
		)
		(fp_line
			(start 0.7874 -0.4064)
			(end -0.7874 -0.4064)
			(stroke
				(width 0.1524)
				(type default)
			)
			(layer "B.SilkS")
		)
		(fp_line
			(start 0.7874 0.4064)
			(end 0.7874 -0.4064)
			(stroke
				(width 0.1524)
				(type default)
			)
			(layer "B.SilkS")
		)
		(fp_line
			(start -0.67945 -0.3048)
			(end -0.67945 0.3048)
			(stroke
				(width 0.1)
				(type default)
			)
			(layer "B.Fab")
		)
		(fp_line
			(start -0.67945 0.3048)
			(end -0.120396 0.3048)
			(stroke
				(width 0.1)
				(type default)
			)
			(layer "B.Fab")
		)
		(fp_line
			(start -0.12065 -0.3048)
			(end -0.67945 -0.3048)
			(stroke
				(width 0.1)
				(type default)
			)
			(layer "B.Fab")
		)
		(fp_line
			(start -0.12065 -0.2794)
			(end -0.12065 -0.3048)
			(stroke
				(width 0.1)
				(type default)
			)
			(layer "B.Fab")
		)
		(fp_line
			(start -0.120396 0.2794)
			(end 0.12065 0.2794)
			(stroke
				(width 0.1)
				(type default)
			)
			(layer "B.Fab")
		)
		(fp_line
			(start -0.120396 0.3048)
			(end -0.120396 0.2794)
			(stroke
				(width 0.1)
				(type default)
			)
			(layer "B.Fab")
		)
		(fp_line
			(start 0.12065 -0.305054)
			(end 0.12065 -0.2794)
			(stroke
				(width 0.1)
				(type default)
			)
			(layer "B.Fab")
		)
		(fp_line
			(start 0.12065 -0.2794)
			(end -0.12065 -0.2794)
			(stroke
				(width 0.1)
				(type default)
			)
			(layer "B.Fab")
		)
		(fp_line
			(start 0.12065 0.2794)
			(end 0.12065 0.3048)
			(stroke
				(width 0.1)
				(type default)
			)
			(layer "B.Fab")
		)
		(fp_line
			(start 0.12065 0.3048)
			(end 0.67945 0.3048)
			(stroke
				(width 0.1)
				(type default)
			)
			(layer "B.Fab")
		)
		(fp_line
			(start 0.67945 -0.305054)
			(end 0.12065 -0.305054)
			(stroke
				(width 0.1)
				(type default)
			)
			(layer "B.Fab")
		)
		(fp_line
			(start 0.67945 0.3048)
			(end 0.67945 -0.305054)
			(stroke
				(width 0.1)
				(type default)
			)
			(layer "B.Fab")
		)
		(pad "1" smd circle
			(at 0.40005 0 180)
			(size 0 0)
			(layers "B.Cu" "B.Mask" "B.Paste")
			(net "P1V2_AUX")
		)
		(pad "2" smd circle
			(at -0.40005 0 180)
			(size 0 0)
			(layers "B.Cu" "B.Mask" "B.Paste")
			(net "GND")
		)
	)
)
